FILE_TYPE=LIBRARY_PARTS;
primitive 'TCA9548APWR';
  pin
    'A0':
      PIN_NUMBER='(1)';
      INPUT_LOAD='(-0.01,0.01)';
    'A1':
      PIN_NUMBER='(2)';
      INPUT_LOAD='(-0.01,0.01)';
    'RESET#':
      PIN_NUMBER='(3)';
      INPUT_LOAD='(-0.01,0.01)';
    'SD0':
      PIN_NUMBER='(4)';
      BIDIRECTIONAL='TRUE';
      INPUT_LOAD='(-0.01,0.01)';
      OUTPUT_LOAD='(1.0,-1.0)';
    'SC0':
      PIN_NUMBER='(5)';
      BIDIRECTIONAL='TRUE';
      INPUT_LOAD='(-0.01,0.01)';
      OUTPUT_LOAD='(1.0,-1.0)';
    'SD1':
      PIN_NUMBER='(6)';
      BIDIRECTIONAL='TRUE';
      INPUT_LOAD='(-0.01,0.01)';
      OUTPUT_LOAD='(1.0,-1.0)';
    'SC1':
      PIN_NUMBER='(7)';
      BIDIRECTIONAL='TRUE';
      INPUT_LOAD='(-0.01,0.01)';
      OUTPUT_LOAD='(1.0,-1.0)';
    'SD2':
      PIN_NUMBER='(8)';
      BIDIRECTIONAL='TRUE';
      INPUT_LOAD='(-0.01,0.01)';
      OUTPUT_LOAD='(1.0,-1.0)';
    'SC2':
      PIN_NUMBER='(9)';
      BIDIRECTIONAL='TRUE';
      INPUT_LOAD='(-0.01,0.01)';
      OUTPUT_LOAD='(1.0,-1.0)';
    'SD3':
      PIN_NUMBER='(10)';
      BIDIRECTIONAL='TRUE';
      INPUT_LOAD='(-0.01,0.01)';
      OUTPUT_LOAD='(1.0,-1.0)';
    'SC3':
      PIN_NUMBER='(11)';
      BIDIRECTIONAL='TRUE';
      INPUT_LOAD='(-0.01,0.01)';
      OUTPUT_LOAD='(1.0,-1.0)';
    'GND':
      PIN_NUMBER='(12)';
      PINUSE='POWER';
      NO_LOAD_CHECK='Both';
      NO_IO_CHECK='Both';
      NO_ASSERT_CHECK='TRUE';
      NO_DIR_CHECK='TRUE';
      ALLOW_CONNECT='TRUE';
    'VCC':
      PIN_NUMBER='(24)';
      PINUSE='POWER';
      NO_LOAD_CHECK='Both';
      NO_IO_CHECK='Both';
      NO_ASSERT_CHECK='TRUE';
      NO_DIR_CHECK='TRUE';
      ALLOW_CONNECT='TRUE';
    'SDA':
      PIN_NUMBER='(23)';
      BIDIRECTIONAL='TRUE';
      INPUT_LOAD='(-0.01,0.01)';
      OUTPUT_LOAD='(1.0,-1.0)';
    'SCL':
      PIN_NUMBER='(22)';
      BIDIRECTIONAL='TRUE';
      INPUT_LOAD='(-0.01,0.01)';
      OUTPUT_LOAD='(1.0,-1.0)';
    'A2':
      PIN_NUMBER='(21)';
      INPUT_LOAD='(-0.01,0.01)';
    'SC7':
      PIN_NUMBER='(20)';
      BIDIRECTIONAL='TRUE';
      INPUT_LOAD='(-0.01,0.01)';
      OUTPUT_LOAD='(1.0,-1.0)';
    'SD7':
      PIN_NUMBER='(19)';
      BIDIRECTIONAL='TRUE';
      INPUT_LOAD='(-0.01,0.01)';
      OUTPUT_LOAD='(1.0,-1.0)';
    'SC6':
      PIN_NUMBER='(18)';
      BIDIRECTIONAL='TRUE';
      INPUT_LOAD='(-0.01,0.01)';
      OUTPUT_LOAD='(1.0,-1.0)';
    'SD6':
      PIN_NUMBER='(17)';
      BIDIRECTIONAL='TRUE';
      INPUT_LOAD='(-0.01,0.01)';
      OUTPUT_LOAD='(1.0,-1.0)';
    'SC5':
      PIN_NUMBER='(16)';
      BIDIRECTIONAL='TRUE';
      INPUT_LOAD='(-0.01,0.01)';
      OUTPUT_LOAD='(1.0,-1.0)';
    'SD5':
      PIN_NUMBER='(15)';
      BIDIRECTIONAL='TRUE';
      INPUT_LOAD='(-0.01,0.01)';
      OUTPUT_LOAD='(1.0,-1.0)';
    'SC4':
      PIN_NUMBER='(14)';
      BIDIRECTIONAL='TRUE';
      INPUT_LOAD='(-0.01,0.01)';
      OUTPUT_LOAD='(1.0,-1.0)';
    'SD4':
      PIN_NUMBER='(13)';
      BIDIRECTIONAL='TRUE';
      INPUT_LOAD='(-0.01,0.01)';
      OUTPUT_LOAD='(1.0,-1.0)';
  end_pin;
  body
    PART_NAME='TCA9548APWR';
    BODY_NAME='TCA9548APWR';
    PHYS_DES_PREFIX='U';
    CLASS='IC';
  end_body;
end_primitive;

END.
